FILE_TYPE = CONNECTIVITY;
{Allegro Design Entry HDL 17.2-2016 S081 (4005846) 1/11/2022}
"PAGE_NUMBER" = 123;
0"NC";
END.
